(kicad_pcb
	(version 20241229)
	(generator "pcbnew")
	(generator_version "9.0")
	(general
		(thickness 1.6296)
		(legacy_teardrops no)
	)
	(paper "A3")
	(title_block
		(title "Thunderbolt to 10GbE adapter")
		(date "2026-04-21")
		(rev "1.1.0")
		(company "Antmicro Ltd")
		(comment 1 "www.antmicro.com")
		(comment 9 "footprints 454-458 of 703")
	)
	(layers
		(0 "F.Cu" signal)
		(4 "In1.Cu" signal)
		(6 "In2.Cu" signal)
		(8 "In3.Cu" signal)
		(10 "In4.Cu" signal)
		(12 "In5.Cu" signal)
		(14 "In6.Cu" signal)
		(2 "B.Cu" signal)
		(9 "F.Adhes" user "F.Adhesive")
		(11 "B.Adhes" user "B.Adhesive")
		(13 "F.Paste" user)
		(15 "B.Paste" user)
		(5 "F.SilkS" user "F.Silkscreen")
		(7 "B.SilkS" user "B.Silkscreen")
		(1 "F.Mask" user)
		(3 "B.Mask" user)
		(17 "Dwgs.User" user "User.Drawings")
		(19 "Cmts.User" user "User.Comments")
		(21 "Eco1.User" user "User.Eco1")
		(23 "Eco2.User" user "User.Eco2")
		(25 "Edge.Cuts" user)
		(27 "Margin" user)
		(31 "F.CrtYd" user "F.Courtyard")
		(29 "B.CrtYd" user "B.Courtyard")
		(35 "F.Fab" user)
		(33 "B.Fab" user)
	)
	(footprint "antmicro-footprints:R_0402_1005Metric"
		(layer "B.Cu")
		(at 136.5 119.15)
		(descr "Resistor SMD 0402")
		(tags "resistor SMD 0402")
		(property "Reference" "R60"
			(at 19.525001 -7.450001 180)
			(layer "B.SilkS")
			(effects
				(font
					(size 0.7 0.7)
					(thickness 0.15)
				)
				(justify mirror)
			)
		)
		(property "Value" "R_100k_0402"
			(at -1.011843 -1.772047 180)
			(layer "B.Fab")
			(effects
				(font
					(size 0.7 0.7)
					(thickness 0.15)
				)
				(justify left bottom mirror)
			)
		)
		(property "Datasheet" "https://www.bourns.com/docs/product-datasheets/cr.pdf"
			(at 0 0 180)
			(layer "B.Fab")
			(hide yes)
			(effects
				(font
					(size 1.27 1.27)
					(thickness 0.15)
				)
				(justify mirror)
			)
		)
		(property "Description" "SMD Chip Resistor, 100 kohm, ± 1%, 62.5 mW, 0402 [1005 Metric], Thick Film, General Purpose"
			(at 0 0 180)
			(layer "B.Fab")
			(hide yes)
			(effects
				(font
					(size 1.27 1.27)
					(thickness 0.15)
				)
				(justify mirror)
			)
		)
		(property "MPN" "CR0402-FX-1003GLF"
			(at 0 0 0)
			(unlocked yes)
			(layer "B.Fab")
			(hide yes)
			(effects
				(font
					(size 1 1)
					(thickness 0.15)
				)
				(justify mirror)
			)
		)
		(property "Manufacturer" "Bourns"
			(at 0 0 0)
			(unlocked yes)
			(layer "B.Fab")
			(hide yes)
			(effects
				(font
					(size 1 1)
					(thickness 0.15)
				)
				(justify mirror)
			)
		)
		(property "License" "Apache-2.0"
			(at 0 0 0)
			(unlocked yes)
			(layer "B.Fab")
			(hide yes)
			(effects
				(font
					(size 1 1)
					(thickness 0.15)
				)
				(justify mirror)
			)
		)
		(property "Val" "100k"
			(at 0 0 0)
			(unlocked yes)
			(layer "B.Fab")
			(hide yes)
			(effects
				(font
					(size 1 1)
					(thickness 0.15)
				)
				(justify mirror)
			)
		)
		(property "Tolerance" "1%"
			(at 0 0 0)
			(unlocked yes)
			(layer "B.Fab")
			(hide yes)
			(effects
				(font
					(size 1 1)
					(thickness 0.15)
				)
				(justify mirror)
			)
		)
		(property "Author" "Antmicro"
			(at 0 0 0)
			(unlocked yes)
			(layer "B.Fab")
			(hide yes)
			(effects
				(font
					(size 1 1)
					(thickness 0.15)
				)
				(justify mirror)
			)
		)
		(sheetname "/TB Controller/")
		(sheetfile "tb.kicad_sch")
		(attr smd)
		(fp_rect
			(start -0.925 0.47)
			(end 0.925 -0.47)
			(stroke
				(width 0.05)
				(type default)
			)
			(fill no)
			(layer "B.CrtYd")
		)
		(fp_rect
			(start -0.5 0.25)
			(end 0.5 -0.25)
			(stroke
				(width 0.15)
				(type solid)
			)
			(fill no)
			(layer "B.Fab")
		)
		(fp_text user "License: Apache-2.0"
			(at -0.95 -5.169 180)
			(layer "B.Fab")
			(effects
				(font
					(size 0.7 0.7)
					(thickness 0.15)
				)
				(justify left bottom mirror)
			)
		)
		(fp_text user "${REFERENCE}"
			(at -0.95 -3.168 180)
			(layer "B.Fab")
			(effects
				(font
					(size 0.7 0.7)
					(thickness 0.15)
				)
				(justify left bottom mirror)
			)
		)
		(fp_text user "Author: Antmicro"
			(at -0.95 -4.169 180)
			(layer "B.Fab")
			(effects
				(font
					(size 0.7 0.7)
					(thickness 0.15)
				)
				(justify left bottom mirror)
			)
		)
		(pad "1" smd roundrect
			(at -0.48 0)
			(size 0.59 0.64)
			(layers "B.Cu" "B.Mask" "B.Paste")
			(roundrect_rratio 0.25)
			(net 233 "Net-(U4E-PB_DPSRC_HPD)")
			(pintype "passive")
		)
		(pad "2" smd roundrect
			(at 0.48 0)
			(size 0.59 0.64)
			(layers "B.Cu" "B.Mask" "B.Paste")
			(roundrect_rratio 0.25)
			(net 23 "GND")
			(pintype "passive")
		)
	)
	(footprint "antmicro-footprints:TP_SMD_0.75mm"
		(layer "B.Cu")
		(at 155.881865 78.760117 180)
		(property "Reference" "TP34"
			(at -20.978136 -8.839883 0)
			(layer "B.SilkS")
			(effects
				(font
					(size 0.7 0.7)
					(thickness 0.15)
				)
				(justify mirror)
			)
		)
		(property "Value" "TP_0.75mm_SMD"
			(at 0 -1.2 0)
			(layer "B.Fab")
			(effects
				(font
					(size 0.7 0.7)
					(thickness 0.15)
				)
				(justify left bottom mirror)
			)
		)
		(property "Description" "SMT test point"
			(at 0 0 0)
			(layer "B.Fab")
			(hide yes)
			(effects
				(font
					(size 1.27 1.27)
					(thickness 0.15)
				)
				(justify mirror)
			)
		)
		(property "MPN" ""
			(at 0 0 180)
			(unlocked yes)
			(layer "B.Fab")
			(hide yes)
			(effects
				(font
					(size 1 1)
					(thickness 0.15)
				)
				(justify mirror)
			)
		)
		(property "Manufacturer" ""
			(at 0 0 180)
			(unlocked yes)
			(layer "B.Fab")
			(hide yes)
			(effects
				(font
					(size 1 1)
					(thickness 0.15)
				)
				(justify mirror)
			)
		)
		(property "Author" "Antmicro"
			(at 0 0 180)
			(unlocked yes)
			(layer "B.Fab")
			(hide yes)
			(effects
				(font
					(size 1 1)
					(thickness 0.15)
				)
				(justify mirror)
			)
		)
		(property "License" "Apache-2.0"
			(at 0 0 180)
			(unlocked yes)
			(layer "B.Fab")
			(hide yes)
			(effects
				(font
					(size 1 1)
					(thickness 0.15)
				)
				(justify mirror)
			)
		)
		(sheetname "/X710-AT2 Misc/")
		(sheetfile "x710-at2-mics.kicad_sch")
		(attr exclude_from_pos_files exclude_from_bom)
		(fp_circle
			(center 0 0)
			(end 0.475 0)
			(stroke
				(width 0.05)
				(type default)
			)
			(fill no)
			(layer "B.CrtYd")
		)
		(fp_text user "License: Apache-2.0"
			(at -0.4 -5.101 0)
			(layer "B.Fab")
			(effects
				(font
					(size 0.7 0.7)
					(thickness 0.15)
				)
				(justify left bottom mirror)
			)
		)
		(fp_text user "Author: Antmicro"
			(at -0.4 -3.901 0)
			(layer "B.Fab")
			(effects
				(font
					(size 0.7 0.7)
					(thickness 0.15)
				)
				(justify left bottom mirror)
			)
		)
		(fp_text user "${REFERENCE}"
			(at -0.4 -2.7 0)
			(layer "B.Fab")
			(effects
				(font
					(size 0.7 0.7)
					(thickness 0.15)
				)
				(justify left bottom mirror)
			)
		)
		(pad "1" smd circle
			(at 0 0 180)
			(size 0.75 0.75)
			(layers "B.Cu" "B.Mask")
			(net 107 "/X710-AT2 Misc/PHY_TDO")
			(pinfunction "1")
			(pintype "passive")
		)
	)
	(footprint "antmicro-footprints:C_0402_1005Metric"
		(layer "B.Cu")
		(at 133.840001 135.089997 -90)
		(descr "Capacitor SMD 0402")
		(tags "capacitor SMD 0402")
		(property "Reference" "C19"
			(at -8.339997 -19.525001 90)
			(layer "B.SilkS")
			(effects
				(font
					(size 0.7 0.7)
					(thickness 0.15)
				)
				(justify mirror)
			)
		)
		(property "Value" "C_1u_0402"
			(at -1.022927 -2.155213 90)
			(layer "B.Fab")
			(effects
				(font
					(size 0.7 0.7)
					(thickness 0.15)
				)
				(justify left bottom mirror)
			)
		)
		(property "Datasheet" "https://product.tdk.com/en/search/capacitor/ceramic/mlcc/info?part_no=C1005X6S1A105K050BC"
			(at 0 0 90)
			(layer "B.Fab")
			(hide yes)
			(effects
				(font
					(size 1.27 1.27)
					(thickness 0.15)
				)
				(justify mirror)
			)
		)
		(property "Description" "SMD Multilayer Ceramic Capacitor, 1 µF, 10 V, 0402 [1005 Metric], ± 10%, X6S, C"
			(at 0 0 90)
			(layer "B.Fab")
			(hide yes)
			(effects
				(font
					(size 1.27 1.27)
					(thickness 0.15)
				)
				(justify mirror)
			)
		)
		(property "MPN" "C1005X6S1A105K050BC"
			(at 0 0 270)
			(unlocked yes)
			(layer "B.Fab")
			(hide yes)
			(effects
				(font
					(size 1 1)
					(thickness 0.15)
				)
				(justify mirror)
			)
		)
		(property "Manufacturer" "TDK"
			(at 0 0 270)
			(unlocked yes)
			(layer "B.Fab")
			(hide yes)
			(effects
				(font
					(size 1 1)
					(thickness 0.15)
				)
				(justify mirror)
			)
		)
		(property "License" "Apache-2.0"
			(at 0 0 270)
			(unlocked yes)
			(layer "B.Fab")
			(hide yes)
			(effects
				(font
					(size 1 1)
					(thickness 0.15)
				)
				(justify mirror)
			)
		)
		(property "Val" "1u"
			(at 0 0 270)
			(unlocked yes)
			(layer "B.Fab")
			(hide yes)
			(effects
				(font
					(size 1 1)
					(thickness 0.15)
				)
				(justify mirror)
			)
		)
		(property "Voltage" ""
			(at 0 0 270)
			(unlocked yes)
			(layer "B.Fab")
			(hide yes)
			(effects
				(font
					(size 1 1)
					(thickness 0.15)
				)
				(justify mirror)
			)
		)
		(property "Dielectric" ""
			(at 0 0 270)
			(unlocked yes)
			(layer "B.Fab")
			(hide yes)
			(effects
				(font
					(size 1 1)
					(thickness 0.15)
				)
				(justify mirror)
			)
		)
		(property "Author" "Antmicro"
			(at 0 0 270)
			(unlocked yes)
			(layer "B.Fab")
			(hide yes)
			(effects
				(font
					(size 1 1)
					(thickness 0.15)
				)
				(justify mirror)
			)
		)
		(sheetname "/PD and TB DC-DC/")
		(sheetfile "PD_and_TB_DC_DC.kicad_sch")
		(attr smd)
		(fp_rect
			(start -0.925 0.47)
			(end 0.925 -0.47)
			(stroke
				(width 0.05)
				(type default)
			)
			(fill no)
			(layer "B.CrtYd")
		)
		(fp_line
			(start -0.494 0.25)
			(end 0.504 0.25)
			(stroke
				(width 0.15)
				(type solid)
			)
			(layer "B.Fab")
		)
		(fp_line
			(start 0.504 0.25)
			(end 0.504 -0.248)
			(stroke
				(width 0.15)
				(type solid)
			)
			(layer "B.Fab")
		)
		(fp_line
			(start -0.494 -0.248)
			(end -0.494 0.25)
			(stroke
				(width 0.15)
				(type solid)
			)
			(layer "B.Fab")
		)
		(fp_line
			(start 0.504 -0.248)
			(end -0.494 -0.248)
			(stroke
				(width 0.15)
				(type solid)
			)
			(layer "B.Fab")
		)
		(fp_text user "Author: Antmicro"
			(at -0.939 -3.399 90)
			(layer "B.Fab")
			(effects
				(font
					(size 0.7 0.7)
					(thickness 0.15)
				)
				(justify left bottom mirror)
			)
		)
		(fp_text user "License: Apache-2.0"
			(at -0.939 -5.799 90)
			(layer "B.Fab")
			(effects
				(font
					(size 0.7 0.7)
					(thickness 0.15)
				)
				(justify left bottom mirror)
			)
		)
		(fp_text user "${REFERENCE}"
			(at -0.939 -4.599 90)
			(layer "B.Fab")
			(effects
				(font
					(size 0.7 0.7)
					(thickness 0.15)
				)
				(justify left bottom mirror)
			)
		)
		(pad "1" smd roundrect
			(at -0.48 0 270)
			(size 0.59 0.64)
			(layers "B.Cu" "B.Mask" "B.Paste")
			(roundrect_rratio 0.25)
			(net 171 "Net-(U3-VOUT_3V3)")
			(pintype "passive")
		)
		(pad "2" smd roundrect
			(at 0.48 0 270)
			(size 0.59 0.64)
			(layers "B.Cu" "B.Mask" "B.Paste")
			(roundrect_rratio 0.25)
			(net 23 "GND")
			(pintype "passive")
		)
	)
	(footprint "antmicro-footprints:R_0402_1005Metric"
		(layer "B.Cu")
		(at 136.500002 117.150001)
		(descr "Resistor SMD 0402")
		(tags "resistor SMD 0402")
		(property "Reference" "R45"
			(at 19.525001 -7.450001 180)
			(layer "B.SilkS")
			(effects
				(font
					(size 0.7 0.7)
					(thickness 0.15)
				)
				(justify mirror)
			)
		)
		(property "Value" "R_10k_0402"
			(at -1.011843 -1.772047 180)
			(layer "B.Fab")
			(effects
				(font
					(size 0.7 0.7)
					(thickness 0.15)
				)
				(justify left bottom mirror)
			)
		)
		(property "Datasheet" "https://www.bourns.com/docs/product-datasheets/cr.pdf"
			(at 0 0 180)
			(layer "B.Fab")
			(hide yes)
			(effects
				(font
					(size 1.27 1.27)
					(thickness 0.15)
				)
				(justify mirror)
			)
		)
		(property "Description" "SMD Chip Resistor, 10 kohm, ± 1%, 62.5 mW, 0402 [1005 Metric], Thick Film, General Purpose"
			(at 0 0 180)
			(layer "B.Fab")
			(hide yes)
			(effects
				(font
					(size 1.27 1.27)
					(thickness 0.15)
				)
				(justify mirror)
			)
		)
		(property "MPN" "CR0402-FX-1002GLF"
			(at 0 0 0)
			(unlocked yes)
			(layer "B.Fab")
			(hide yes)
			(effects
				(font
					(size 1 1)
					(thickness 0.15)
				)
				(justify mirror)
			)
		)
		(property "Manufacturer" "Bourns"
			(at 0 0 0)
			(unlocked yes)
			(layer "B.Fab")
			(hide yes)
			(effects
				(font
					(size 1 1)
					(thickness 0.15)
				)
				(justify mirror)
			)
		)
		(property "License" "Apache-2.0"
			(at 0 0 0)
			(unlocked yes)
			(layer "B.Fab")
			(hide yes)
			(effects
				(font
					(size 1 1)
					(thickness 0.15)
				)
				(justify mirror)
			)
		)
		(property "Val" "10k"
			(at 0 0 0)
			(unlocked yes)
			(layer "B.Fab")
			(hide yes)
			(effects
				(font
					(size 1 1)
					(thickness 0.15)
				)
				(justify mirror)
			)
		)
		(property "Tolerance" "1%"
			(at 0 0 0)
			(unlocked yes)
			(layer "B.Fab")
			(hide yes)
			(effects
				(font
					(size 1 1)
					(thickness 0.15)
				)
				(justify mirror)
			)
		)
		(property "Author" "Antmicro"
			(at 0 0 0)
			(unlocked yes)
			(layer "B.Fab")
			(hide yes)
			(effects
				(font
					(size 1 1)
					(thickness 0.15)
				)
				(justify mirror)
			)
		)
		(sheetname "/TB Controller/")
		(sheetfile "tb.kicad_sch")
		(attr smd)
		(fp_rect
			(start -0.925 0.47)
			(end 0.925 -0.47)
			(stroke
				(width 0.05)
				(type default)
			)
			(fill no)
			(layer "B.CrtYd")
		)
		(fp_rect
			(start -0.5 0.25)
			(end 0.5 -0.25)
			(stroke
				(width 0.15)
				(type solid)
			)
			(fill no)
			(layer "B.Fab")
		)
		(fp_text user "${REFERENCE}"
			(at -0.95 -3.168 180)
			(layer "B.Fab")
			(effects
				(font
					(size 0.7 0.7)
					(thickness 0.15)
				)
				(justify left bottom mirror)
			)
		)
		(fp_text user "Author: Antmicro"
			(at -0.95 -4.169 180)
			(layer "B.Fab")
			(effects
				(font
					(size 0.7 0.7)
					(thickness 0.15)
				)
				(justify left bottom mirror)
			)
		)
		(fp_text user "License: Apache-2.0"
			(at -0.95 -5.169 180)
			(layer "B.Fab")
			(effects
				(font
					(size 0.7 0.7)
					(thickness 0.15)
				)
				(justify left bottom mirror)
			)
		)
		(pad "1" smd roundrect
			(at -0.48 0)
			(size 0.59 0.64)
			(layers "B.Cu" "B.Mask" "B.Paste")
			(roundrect_rratio 0.25)
			(net 188 "Net-(U4C-GPIO_5)")
			(pintype "passive")
		)
		(pad "2" smd roundrect
			(at 0.48 0)
			(size 0.59 0.64)
			(layers "B.Cu" "B.Mask" "B.Paste")
			(roundrect_rratio 0.25)
			(net 23 "GND")
			(pintype "passive")
		)
	)
	(footprint "antmicro-footprints:C_0402_1005Metric"
		(layer "B.Cu")
		(at 146 105 90)
		(descr "Capacitor SMD 0402")
		(tags "capacitor SMD 0402")
		(property "Reference" "C153"
			(at 1 1.5 270)
			(layer "B.SilkS")
			(effects
				(font
					(size 0.7 0.7)
					(thickness 0.15)
				)
				(justify left bottom mirror)
			)
		)
		(property "Value" "C_100n_0402"
			(at -1.022927 -2.155213 270)
			(layer "B.Fab")
			(effects
				(font
					(size 0.7 0.7)
					(thickness 0.15)
				)
				(justify left bottom mirror)
			)
		)
		(property "Datasheet" "https://www.murata.com/products/productdetail?partno=GRM155R61H104KE14%23"
			(at 0 0 270)
			(layer "B.Fab")
			(hide yes)
			(effects
				(font
					(size 1.27 1.27)
					(thickness 0.15)
				)
				(justify mirror)
			)
		)
		(property "Description" "SMD Multilayer Ceramic Capacitor, 0.1 µF, 50 V, 0402 [1005 Metric], ± 10%, X5R, GRM Series"
			(at 0 0 270)
			(layer "B.Fab")
			(hide yes)
			(effects
				(font
					(size 1.27 1.27)
					(thickness 0.15)
				)
				(justify mirror)
			)
		)
		(property "MPN" "GRM155R61H104KE14D"
			(at 0 0 90)
			(unlocked yes)
			(layer "B.Fab")
			(hide yes)
			(effects
				(font
					(size 1 1)
					(thickness 0.15)
				)
				(justify mirror)
			)
		)
		(property "Manufacturer" "Murata"
			(at 0 0 90)
			(unlocked yes)
			(layer "B.Fab")
			(hide yes)
			(effects
				(font
					(size 1 1)
					(thickness 0.15)
				)
				(justify mirror)
			)
		)
		(property "License" "Apache-2.0"
			(at 0 0 90)
			(unlocked yes)
			(layer "B.Fab")
			(hide yes)
			(effects
				(font
					(size 1 1)
					(thickness 0.15)
				)
				(justify mirror)
			)
		)
		(property "Author" "Antmicro"
			(at 0 0 90)
			(unlocked yes)
			(layer "B.Fab")
			(hide yes)
			(effects
				(font
					(size 1 1)
					(thickness 0.15)
				)
				(justify mirror)
			)
		)
		(property "Val" "100n"
			(at 0 0 90)
			(unlocked yes)
			(layer "B.Fab")
			(hide yes)
			(effects
				(font
					(size 1 1)
					(thickness 0.15)
				)
				(justify mirror)
			)
		)
		(property "Voltage" "50V"
			(at 0 0 90)
			(unlocked yes)
			(layer "B.Fab")
			(hide yes)
			(effects
				(font
					(size 1 1)
					(thickness 0.15)
				)
				(justify mirror)
			)
		)
		(property "Dielectric" "X5R"
			(at 0 0 90)
			(unlocked yes)
			(layer "B.Fab")
			(hide yes)
			(effects
				(font
					(size 1 1)
					(thickness 0.15)
				)
				(justify mirror)
			)
		)
		(sheetname "/X710 DCDC converters/")
		(sheetfile "DCDC_converters_X710.kicad_sch")
		(attr smd)
		(fp_rect
			(start -0.925 0.47)
			(end 0.925 -0.47)
			(stroke
				(width 0.05)
				(type default)
			)
			(fill no)
			(layer "B.CrtYd")
		)
		(fp_line
			(start 0.504 -0.248)
			(end -0.494 -0.248)
			(stroke
				(width 0.15)
				(type solid)
			)
			(layer "B.Fab")
		)
		(fp_line
			(start -0.494 -0.248)
			(end -0.494 0.25)
			(stroke
				(width 0.15)
				(type solid)
			)
			(layer "B.Fab")
		)
		(fp_line
			(start 0.504 0.25)
			(end 0.504 -0.248)
			(stroke
				(width 0.15)
				(type solid)
			)
			(layer "B.Fab")
		)
		(fp_line
			(start -0.494 0.25)
			(end 0.504 0.25)
			(stroke
				(width 0.15)
				(type solid)
			)
			(layer "B.Fab")
		)
		(fp_text user "License: Apache-2.0"
			(at -0.939 -5.799 270)
			(layer "B.Fab")
			(effects
				(font
					(size 0.7 0.7)
					(thickness 0.15)
				)
				(justify left bottom mirror)
			)
		)
		(fp_text user "Author: Antmicro"
			(at -0.939 -3.399 270)
			(layer "B.Fab")
			(effects
				(font
					(size 0.7 0.7)
					(thickness 0.15)
				)
				(justify left bottom mirror)
			)
		)
		(fp_text user "${REFERENCE}"
			(at -0.939 -4.599 270)
			(layer "B.Fab")
			(effects
				(font
					(size 0.7 0.7)
					(thickness 0.15)
				)
				(justify left bottom mirror)
			)
		)
		(pad "1" smd roundrect
			(at -0.48 0 90)
			(size 0.59 0.64)
			(layers "B.Cu" "B.Mask" "B.Paste")
			(roundrect_rratio 0.25)
			(net 23 "GND")
			(pintype "passive")
		)
		(pad "2" smd roundrect
			(at 0.48 0 90)
			(size 0.59 0.64)
			(layers "B.Cu" "B.Mask" "B.Paste")
			(roundrect_rratio 0.25)
			(net 341 "/X710 DCDC converters/+DVDD_OUT")
			(pintype "passive")
		)
	)
)
